(kicad_pcb
	(version 20260206)
	(generator "pcbnew")
	(generator_version "10.0")
	(general
		(thickness 1.6)
		(legacy_teardrops no)
	)
	(paper "A4")
	(title_block
		(title "peb — Lightning_PEB_BRD.brd")
		(comment 1 "Lightning (Wiwynn / Facebook NVMe JBOF) / footprints 65-72 of 2563")
	)
	(layers
		(0 "F.Cu" signal "TOP")
		(4 "In1.Cu" signal "L2GND")
		(6 "In2.Cu" signal "L3")
		(8 "In3.Cu" signal "L4VCC")
		(10 "In4.Cu" signal "L5VCC")
		(12 "In5.Cu" signal "L6")
		(14 "In6.Cu" signal "L7GND")
		(2 "B.Cu" signal "BOTTOM")
		(9 "F.Adhes" user "F.Adhesive")
		(11 "B.Adhes" user "B.Adhesive")
		(13 "F.Paste" user "Package Geometry/Pastemask Top")
		(15 "B.Paste" user "Package Geometry/Pastemask Bottom")
		(5 "F.SilkS" user "Ref Des/Silkscreen Top")
		(7 "B.SilkS" user "Ref Des/Silkscreen Bottom")
		(1 "F.Mask" user "Board Geometry/Soldermask Top")
		(3 "B.Mask" user "Board Geometry/Soldermask Bottom")
		(17 "Dwgs.User" user "User.Drawings")
		(19 "Cmts.User" user "User.Comments")
		(21 "Eco1.User" user "User.Eco1")
		(23 "Eco2.User" user "User.Eco2")
		(25 "Edge.Cuts" user "Board Geometry/Outline")
		(27 "Margin" user)
		(31 "F.CrtYd" user "Package Geometry/Place Bound Top")
		(29 "B.CrtYd" user "Package Geometry/Place Bound Bottom")
		(35 "F.Fab" user "Ref Des/Assembly Top")
		(33 "B.Fab" user "Ref Des/Assembly Bottom")
	)
	(footprint ""
		(layer "F.Cu")
		(at 52.578 -192.913 90)
		(property "Reference" "C704"
			(at 0 0 90)
			(layer "F.SilkS")
			(hide yes)
			(effects
				(font
					(size 1.27 1.27)
				)
			)
		)
		(property "Value" "SC220P50V3JN-GP"
			(at 0 -2.8194 90)
			(unlocked yes)
			(layer "F.Fab")
			(hide yes)
			(effects
				(font
					(size 1.016 1.016)
					(thickness 0.1524)
				)
			)
		)
		(property "Device Type" "C603H36"
			(at 0 -4.3434 90)
			(unlocked yes)
			(layer "F.Fab")
			(hide yes)
			(effects
				(font
					(size 1.016 1.016)
					(thickness 0.1524)
				)
			)
		)
		(duplicate_pad_numbers_are_jumpers no)
		(fp_line
			(start 0.508 0)
			(end -0.508 0)
			(stroke
				(width 0.2032)
				(type default)
			)
			(layer "F.SilkS")
		)
		(fp_rect
			(start -0.5842 1.3335)
			(end 0.5842 -1.3335)
			(stroke
				(width 0)
				(type default)
			)
			(fill no)
			(layer "F.CrtYd")
		)
		(fp_rect
			(start -0.5842 1.3335)
			(end 0.5842 -1.3335)
			(stroke
				(width 0)
				(type default)
			)
			(fill no)
			(layer "F.Fab")
		)
		(pad "1" smd custom
			(at 0 -0.762 90)
			(size 0.2159 0.2159)
			(layers "F.Cu" "F.Mask" "F.Paste")
			(net "BMC_I2C7_B_DBP_SCL_R")
			(options
				(clearance outline)
				(anchor circle)
			)
			(primitives
				(gr_poly
					(pts
						(arc
							(start -0.3302 -0.4318)
							(mid -0.402042 -0.402042)
							(end -0.4318 -0.3302)
						)
						(arc
							(start -0.4318 0.3302)
							(mid -0.402042 0.402042)
							(end -0.3302 0.4318)
						)
						(arc
							(start 0.3302 0.4318)
							(mid 0.402042 0.402042)
							(end 0.4318 0.3302)
						)
						(arc
							(start 0.4318 -0.3302)
							(mid 0.402042 -0.402042)
							(end 0.3302 -0.4318)
						)
					)
					(width 0)
					(fill yes)
				)
			)
		)
		(pad "2" smd custom
			(at 0 0.762 90)
			(size 0.2159 0.2159)
			(layers "F.Cu" "F.Mask" "F.Paste")
			(net "GND")
			(options
				(clearance outline)
				(anchor circle)
			)
			(primitives
				(gr_poly
					(pts
						(arc
							(start -0.3302 -0.4318)
							(mid -0.402042 -0.402042)
							(end -0.4318 -0.3302)
						)
						(arc
							(start -0.4318 0.3302)
							(mid -0.402042 0.402042)
							(end -0.3302 0.4318)
						)
						(arc
							(start 0.3302 0.4318)
							(mid 0.402042 0.402042)
							(end 0.4318 0.3302)
						)
						(arc
							(start 0.4318 -0.3302)
							(mid 0.402042 -0.402042)
							(end 0.3302 -0.4318)
						)
					)
					(width 0)
					(fill yes)
				)
			)
		)
	)
	(footprint ""
		(layer "F.Cu")
		(at 303.53 -68.834 180)
		(property "Reference" "C458"
			(at 0 0 180)
			(layer "F.SilkS")
			(hide yes)
			(effects
				(font
					(size 1.27 1.27)
				)
			)
		)
		(property "Value" "SC10U16V5KX-1-GP"
			(at -0.0762 -6.1214 180)
			(unlocked yes)
			(layer "F.Fab")
			(hide yes)
			(effects
				(font
					(size 1.016 1.016)
					(thickness 0.1524)
				)
			)
		)
		(property "Device Type" "C805H54"
			(at -0.0762 -8.1534 180)
			(unlocked yes)
			(layer "F.Fab")
			(hide yes)
			(effects
				(font
					(size 1.016 1.016)
					(thickness 0.1524)
				)
			)
		)
		(duplicate_pad_numbers_are_jumpers no)
		(fp_line
			(start 0.635 0)
			(end -0.635 0)
			(stroke
				(width 0.508)
				(type default)
			)
			(layer "F.SilkS")
		)
		(fp_rect
			(start -0.9652 1.778)
			(end 0.9652 -1.778)
			(stroke
				(width 0)
				(type default)
			)
			(fill no)
			(layer "F.CrtYd")
		)
		(fp_poly
			(pts
				(xy -0.9652 -1.778) (xy 0.9652 -1.778) (xy 0.9652 1.778) (xy -0.9652 1.778)
			)
			(stroke
				(width 0)
				(type default)
			)
			(fill no)
			(layer "F.Fab")
		)
		(pad "1" smd rect
			(at 0 -0.9652 180)
			(size 1.397 1.143)
			(layers "F.Cu" "F.Mask" "F.Paste")
			(net "DUT_VDD")
		)
		(pad "2" smd rect
			(at 0 0.9652 180)
			(size 1.397 1.143)
			(layers "F.Cu" "F.Mask" "F.Paste")
			(net "GND")
		)
	)
	(footprint ""
		(layer "F.Cu")
		(at 133.453886 -81.925414)
		(property "Reference" "C306"
			(at 0 0 0)
			(layer "F.SilkS")
			(hide yes)
			(effects
				(font
					(size 1.27 1.27)
				)
			)
		)
		(property "Value" "SC3D9P50V2CN-1GP"
			(at 1.1811 -2.7051 0)
			(unlocked yes)
			(layer "F.Fab")
			(hide yes)
			(effects
				(font
					(size 1.016 1.016)
					(thickness 0.1524)
				)
			)
		)
		(property "Device Type" "C402H22"
			(at 1.1811 -4.2291 0)
			(unlocked yes)
			(layer "F.Fab")
			(hide yes)
			(effects
				(font
					(size 1.016 1.016)
					(thickness 0.1524)
				)
			)
		)
		(duplicate_pad_numbers_are_jumpers no)
		(fp_rect
			(start -0.4318 0.9525)
			(end 0.4318 -0.9525)
			(stroke
				(width 0)
				(type default)
			)
			(fill no)
			(layer "F.CrtYd")
		)
		(fp_rect
			(start -0.4318 0.9525)
			(end 0.4318 -0.9525)
			(stroke
				(width 0)
				(type default)
			)
			(fill no)
			(layer "F.Fab")
		)
		(pad "1" smd custom
			(at 0 -0.4445)
			(size 0.1524 0.1524)
			(layers "F.Cu" "F.Mask" "F.Paste")
			(net "RTC_OSCI")
			(options
				(clearance outline)
				(anchor circle)
			)
			(primitives
				(gr_poly
					(pts
						(arc
							(start 0.3048 -0.2032)
							(mid 0.275042 -0.275042)
							(end 0.2032 -0.3048)
						)
						(arc
							(start -0.2032 -0.3048)
							(mid -0.275042 -0.275042)
							(end -0.3048 -0.2032)
						)
						(arc
							(start -0.3048 0.2032)
							(mid -0.275042 0.275042)
							(end -0.2032 0.3048)
						)
						(arc
							(start 0.2032 0.3048)
							(mid 0.275042 0.275042)
							(end 0.3048 0.2032)
						)
					)
					(width 0)
					(fill yes)
				)
			)
		)
		(pad "2" smd custom
			(at 0 0.4445)
			(size 0.1524 0.1524)
			(layers "F.Cu" "F.Mask" "F.Paste")
			(net "GND")
			(options
				(clearance outline)
				(anchor circle)
			)
			(primitives
				(gr_poly
					(pts
						(arc
							(start 0.3048 -0.2032)
							(mid 0.275042 -0.275042)
							(end 0.2032 -0.3048)
						)
						(arc
							(start -0.2032 -0.3048)
							(mid -0.275042 -0.275042)
							(end -0.3048 -0.2032)
						)
						(arc
							(start -0.3048 0.2032)
							(mid -0.275042 0.275042)
							(end -0.2032 0.3048)
						)
						(arc
							(start 0.2032 0.3048)
							(mid 0.275042 0.275042)
							(end 0.3048 0.2032)
						)
					)
					(width 0)
					(fill yes)
				)
			)
		)
	)
	(footprint ""
		(layer "F.Cu")
		(at 48.84801 -73.533254 -90)
		(property "Reference" "R942"
			(at 0 0 270)
			(layer "F.SilkS")
			(hide yes)
			(effects
				(font
					(size 1.27 1.27)
				)
			)
		)
		(property "Value" "0R2J-2-GP"
			(at 0.064008 -3.993896 270)
			(unlocked yes)
			(layer "F.Fab")
			(hide yes)
			(effects
				(font
					(size 1.016 1.016)
					(thickness 0.1524)
				)
			)
		)
		(property "Device Type" "R402H16"
			(at 0.064008 -5.517896 270)
			(unlocked yes)
			(layer "F.Fab")
			(hide yes)
			(effects
				(font
					(size 1.016 1.016)
					(thickness 0.1524)
				)
			)
		)
		(duplicate_pad_numbers_are_jumpers no)
		(fp_line
			(start -0.508 -0.9398)
			(end -0.508 0.9398)
			(stroke
				(width 0.1524)
				(type default)
			)
			(layer "F.SilkS")
		)
		(fp_line
			(start 0.508 -0.9398)
			(end -0.508 -0.9398)
			(stroke
				(width 0.1524)
				(type default)
			)
			(layer "F.SilkS")
		)
		(fp_rect
			(start -0.508 0.9398)
			(end 0.508 -0.9398)
			(stroke
				(width 0)
				(type default)
			)
			(fill no)
			(layer "F.CrtYd")
		)
		(fp_rect
			(start -0.508 0.9398)
			(end 0.508 -0.9398)
			(stroke
				(width 0)
				(type default)
			)
			(fill no)
			(layer "F.Fab")
		)
		(pad "1" smd custom
			(at 0 -0.4445 270)
			(size 0.1397 0.1397)
			(layers "F.Cu" "F.Mask" "F.Paste")
			(net "BMC_R_TXD5")
			(options
				(clearance outline)
				(anchor circle)
			)
			(primitives
				(gr_poly
					(pts
						(arc
							(start -0.1778 -0.2794)
							(mid -0.249642 -0.249642)
							(end -0.2794 -0.1778)
						)
						(arc
							(start -0.2794 0.1778)
							(mid -0.249642 0.249642)
							(end -0.1778 0.2794)
						)
						(arc
							(start 0.1778 0.2794)
							(mid 0.249642 0.249642)
							(end 0.2794 0.1778)
						)
						(arc
							(start 0.2794 -0.1778)
							(mid 0.249642 -0.249642)
							(end 0.1778 -0.2794)
						)
					)
					(width 0)
					(fill yes)
				)
			)
		)
		(pad "2" smd custom
			(at 0 0.4445 270)
			(size 0.1397 0.1397)
			(layers "F.Cu" "F.Mask" "F.Paste")
			(net "BMC_TXD5")
			(options
				(clearance outline)
				(anchor circle)
			)
			(primitives
				(gr_poly
					(pts
						(arc
							(start -0.1778 -0.2794)
							(mid -0.249642 -0.249642)
							(end -0.2794 -0.1778)
						)
						(arc
							(start -0.2794 0.1778)
							(mid -0.249642 0.249642)
							(end -0.1778 0.2794)
						)
						(arc
							(start 0.1778 0.2794)
							(mid 0.249642 0.249642)
							(end 0.2794 0.1778)
						)
						(arc
							(start 0.2794 -0.1778)
							(mid 0.249642 -0.249642)
							(end 0.1778 -0.2794)
						)
					)
					(width 0)
					(fill yes)
				)
			)
		)
	)
	(footprint ""
		(layer "F.Cu")
		(at 167.767 -92.0242 90)
		(property "Reference" "TP75"
			(at 0 0 90)
			(layer "F.SilkS")
			(hide yes)
			(effects
				(font
					(size 1.27 1.27)
				)
			)
		)
		(property "Value" "TPAD28-2-GP"
			(at -0.0127 -1.6637 90)
			(unlocked yes)
			(layer "F.Fab")
			(hide yes)
			(effects
				(font
					(size 1.016 1.016)
					(thickness 0.1524)
				)
			)
		)
		(property "Device Type" "TPAD28"
			(at -0.0127 -3.1877 90)
			(unlocked yes)
			(layer "F.Fab")
			(hide yes)
			(effects
				(font
					(size 1.016 1.016)
					(thickness 0.1524)
				)
			)
		)
		(duplicate_pad_numbers_are_jumpers no)
		(fp_poly
			(pts
				(arc
					(start 0 0.3556)
					(mid 0 -0.3556)
					(end 0 0.3556)
				)
			)
			(stroke
				(width 0)
				(type default)
			)
			(fill no)
			(layer "F.CrtYd")
		)
		(fp_poly
			(pts
				(arc
					(start 0 0.6096)
					(mid 0 -0.6096)
					(end 0 0.6096)
				)
			)
			(stroke
				(width 0)
				(type default)
			)
			(fill no)
			(layer "F.Fab")
		)
		(pad "1" smd circle
			(at 0 0 90)
			(size 0.7112 0.7112)
			(layers "F.Cu" "F.Mask" "F.Paste")
			(net "CLKGEN_P2")
		)
	)
	(footprint ""
		(layer "F.Cu")
		(at 224.040446 -203.708 180)
		(property "Reference" "R7934"
			(at 0 0 180)
			(layer "F.SilkS")
			(hide yes)
			(effects
				(font
					(size 1.27 1.27)
				)
			)
		)
		(property "Value" "0R2J-2-GP"
			(at 0.064008 -3.993896 180)
			(unlocked yes)
			(layer "F.Fab")
			(hide yes)
			(effects
				(font
					(size 1.016 1.016)
					(thickness 0.1524)
				)
			)
		)
		(property "Device Type" "R402H16"
			(at 0.064008 -5.517896 180)
			(unlocked yes)
			(layer "F.Fab")
			(hide yes)
			(effects
				(font
					(size 1.016 1.016)
					(thickness 0.1524)
				)
			)
		)
		(duplicate_pad_numbers_are_jumpers no)
		(fp_line
			(start 0.508 -0.9398)
			(end -0.508 -0.9398)
			(stroke
				(width 0.1524)
				(type default)
			)
			(layer "F.SilkS")
		)
		(fp_line
			(start -0.508 -0.9398)
			(end -0.508 0.9398)
			(stroke
				(width 0.1524)
				(type default)
			)
			(layer "F.SilkS")
		)
		(fp_rect
			(start -0.508 0.9398)
			(end 0.508 -0.9398)
			(stroke
				(width 0)
				(type default)
			)
			(fill no)
			(layer "F.CrtYd")
		)
		(fp_rect
			(start -0.508 0.9398)
			(end 0.508 -0.9398)
			(stroke
				(width 0)
				(type default)
			)
			(fill no)
			(layer "F.Fab")
		)
		(pad "1" smd custom
			(at 0 -0.4445 180)
			(size 0.1397 0.1397)
			(layers "F.Cu" "F.Mask" "F.Paste")
			(net "SSD_PRSNT#13")
			(options
				(clearance outline)
				(anchor circle)
			)
			(primitives
				(gr_poly
					(pts
						(arc
							(start -0.1778 -0.2794)
							(mid -0.249642 -0.249642)
							(end -0.2794 -0.1778)
						)
						(arc
							(start -0.2794 0.1778)
							(mid -0.249642 0.249642)
							(end -0.1778 0.2794)
						)
						(arc
							(start 0.1778 0.2794)
							(mid 0.249642 0.249642)
							(end 0.2794 0.1778)
						)
						(arc
							(start 0.2794 -0.1778)
							(mid 0.249642 -0.249642)
							(end 0.1778 -0.2794)
						)
					)
					(width 0)
					(fill yes)
				)
			)
		)
		(pad "2" smd custom
			(at 0 0.4445 180)
			(size 0.1397 0.1397)
			(layers "F.Cu" "F.Mask" "F.Paste")
			(net "SSD_PRSNT#13_R")
			(options
				(clearance outline)
				(anchor circle)
			)
			(primitives
				(gr_poly
					(pts
						(arc
							(start -0.1778 -0.2794)
							(mid -0.249642 -0.249642)
							(end -0.2794 -0.1778)
						)
						(arc
							(start -0.2794 0.1778)
							(mid -0.249642 0.249642)
							(end -0.1778 0.2794)
						)
						(arc
							(start 0.1778 0.2794)
							(mid 0.249642 0.249642)
							(end 0.2794 0.1778)
						)
						(arc
							(start 0.2794 -0.1778)
							(mid 0.249642 -0.249642)
							(end 0.1778 -0.2794)
						)
					)
					(width 0)
					(fill yes)
				)
			)
		)
	)
	(footprint ""
		(layer "F.Cu")
		(at 227.965 -23.241 180)
		(property "Reference" "R3720"
			(at 0 0 180)
			(layer "F.SilkS")
			(hide yes)
			(effects
				(font
					(size 1.27 1.27)
				)
			)
		)
		(property "Value" "4K7R2F-GP"
			(at 0.064008 -3.993896 180)
			(unlocked yes)
			(layer "F.Fab")
			(hide yes)
			(effects
				(font
					(size 1.016 1.016)
					(thickness 0.1524)
				)
			)
		)
		(property "Device Type" "R402H16"
			(at 0.064008 -5.517896 180)
			(unlocked yes)
			(layer "F.Fab")
			(hide yes)
			(effects
				(font
					(size 1.016 1.016)
					(thickness 0.1524)
				)
			)
		)
		(duplicate_pad_numbers_are_jumpers no)
		(fp_line
			(start 0.508 -0.9398)
			(end -0.508 -0.9398)
			(stroke
				(width 0.1524)
				(type default)
			)
			(layer "F.SilkS")
		)
		(fp_line
			(start -0.508 -0.9398)
			(end -0.508 0.9398)
			(stroke
				(width 0.1524)
				(type default)
			)
			(layer "F.SilkS")
		)
		(fp_rect
			(start -0.508 0.9398)
			(end 0.508 -0.9398)
			(stroke
				(width 0)
				(type default)
			)
			(fill no)
			(layer "F.CrtYd")
		)
		(fp_rect
			(start -0.508 0.9398)
			(end 0.508 -0.9398)
			(stroke
				(width 0)
				(type default)
			)
			(fill no)
			(layer "F.Fab")
		)
		(pad "1" smd custom
			(at 0 -0.4445 180)
			(size 0.1397 0.1397)
			(layers "F.Cu" "F.Mask" "F.Paste")
			(net "HOST3_RST_N_LS")
			(options
				(clearance outline)
				(anchor circle)
			)
			(primitives
				(gr_poly
					(pts
						(arc
							(start -0.1778 -0.2794)
							(mid -0.249642 -0.249642)
							(end -0.2794 -0.1778)
						)
						(arc
							(start -0.2794 0.1778)
							(mid -0.249642 0.249642)
							(end -0.1778 0.2794)
						)
						(arc
							(start 0.1778 0.2794)
							(mid 0.249642 0.249642)
							(end 0.2794 0.1778)
						)
						(arc
							(start 0.2794 -0.1778)
							(mid 0.249642 -0.249642)
							(end 0.1778 -0.2794)
						)
					)
					(width 0)
					(fill yes)
				)
			)
		)
		(pad "2" smd custom
			(at 0 0.4445 180)
			(size 0.1397 0.1397)
			(layers "F.Cu" "F.Mask" "F.Paste")
			(net "GND")
			(options
				(clearance outline)
				(anchor circle)
			)
			(primitives
				(gr_poly
					(pts
						(arc
							(start -0.1778 -0.2794)
							(mid -0.249642 -0.249642)
							(end -0.2794 -0.1778)
						)
						(arc
							(start -0.2794 0.1778)
							(mid -0.249642 0.249642)
							(end -0.1778 0.2794)
						)
						(arc
							(start 0.1778 0.2794)
							(mid 0.249642 0.249642)
							(end 0.2794 0.1778)
						)
						(arc
							(start 0.2794 -0.1778)
							(mid 0.249642 -0.249642)
							(end 0.1778 -0.2794)
						)
					)
					(width 0)
					(fill yes)
				)
			)
		)
	)
	(footprint ""
		(layer "F.Cu")
		(at 18.415 -129.667 -90)
		(property "Reference" "R369"
			(at 0 0 270)
			(layer "F.SilkS")
			(hide yes)
			(effects
				(font
					(size 1.27 1.27)
				)
			)
		)
		(property "Value" "3K3R2F-2-GP"
			(at 0.064008 -3.993896 270)
			(unlocked yes)
			(layer "F.Fab")
			(hide yes)
			(effects
				(font
					(size 1.016 1.016)
					(thickness 0.1524)
				)
			)
		)
		(property "Device Type" "R402H16"
			(at 0.064008 -5.517896 270)
			(unlocked yes)
			(layer "F.Fab")
			(hide yes)
			(effects
				(font
					(size 1.016 1.016)
					(thickness 0.1524)
				)
			)
		)
		(duplicate_pad_numbers_are_jumpers no)
		(fp_line
			(start -0.508 -0.9398)
			(end -0.508 0.9398)
			(stroke
				(width 0.1524)
				(type default)
			)
			(layer "F.SilkS")
		)
		(fp_line
			(start 0.508 -0.9398)
			(end -0.508 -0.9398)
			(stroke
				(width 0.1524)
				(type default)
			)
			(layer "F.SilkS")
		)
		(fp_rect
			(start -0.508 0.9398)
			(end 0.508 -0.9398)
			(stroke
				(width 0)
				(type default)
			)
			(fill no)
			(layer "F.CrtYd")
		)
		(fp_rect
			(start -0.508 0.9398)
			(end 0.508 -0.9398)
			(stroke
				(width 0)
				(type default)
			)
			(fill no)
			(layer "F.Fab")
		)
		(pad "1" smd custom
			(at 0 -0.4445 270)
			(size 0.1397 0.1397)
			(layers "F.Cu" "F.Mask" "F.Paste")
			(net "P3V3_STBY")
			(options
				(clearance outline)
				(anchor circle)
			)
			(primitives
				(gr_poly
					(pts
						(arc
							(start -0.1778 -0.2794)
							(mid -0.249642 -0.249642)
							(end -0.2794 -0.1778)
						)
						(arc
							(start -0.2794 0.1778)
							(mid -0.249642 0.249642)
							(end -0.1778 0.2794)
						)
						(arc
							(start 0.1778 0.2794)
							(mid 0.249642 0.249642)
							(end 0.2794 0.1778)
						)
						(arc
							(start 0.2794 -0.1778)
							(mid 0.249642 -0.249642)
							(end 0.1778 -0.2794)
						)
					)
					(width 0)
					(fill yes)
				)
			)
		)
		(pad "2" smd custom
			(at 0 0.4445 270)
			(size 0.1397 0.1397)
			(layers "F.Cu" "F.Mask" "F.Paste")
			(net "ROMA23")
			(options
				(clearance outline)
				(anchor circle)
			)
			(primitives
				(gr_poly
					(pts
						(arc
							(start -0.1778 -0.2794)
							(mid -0.249642 -0.249642)
							(end -0.2794 -0.1778)
						)
						(arc
							(start -0.2794 0.1778)
							(mid -0.249642 0.249642)
							(end -0.1778 0.2794)
						)
						(arc
							(start 0.1778 0.2794)
							(mid 0.249642 0.249642)
							(end 0.2794 0.1778)
						)
						(arc
							(start 0.2794 -0.1778)
							(mid 0.249642 -0.249642)
							(end 0.1778 -0.2794)
						)
					)
					(width 0)
					(fill yes)
				)
			)
		)
	)
)
